FILE_TYPE = CONNECTIVITY;
{Allegro Design Entry HDL 17.2-2016 S081 (4005846) 1/11/2022}
"PAGE_NUMBER" = 102;
0"NC";
1"P3V3_AUX\g";
2"P12V_S3_AUX_CPU1_NVDIMM\g";
3"P12V_S3_AUX_CPU1_NVDIMM\g";
4"P3V3_AUX\g";
5"GND\g";
6"GND\g";
7"GND\g";
8"GND\g";
9"GND\g";
10"M_C_CPU1_SA_DQ<31:0>";
11"M_C_CPU1_SA_CB<7:0>";
12"M_C_CPU1_SB_CB<7:0>";
13"M_C_CPU1_SA_CA<6:0>";
14"M_C_CPU1_SB_CA<6:0>";
15"M_C_CPU1_SB_DQ<31:0>";
16"M_C_CPU1_SB_DQS_DP<9:0>";
17"M_C_CPU1_SA_DQS_DP<9:0>";
18"M_C_CPU1_SB_DQS_DN<9:0>";
19"M_C_CPU1_SA_DQS_DN<9:0>";
20"I3C_SPD_DDRABCD_CPU1_LVC1_SCL_R5";
21"I3C_SPD_DDRABCD_CPU1_LVC1_SDA";
22"PD_CHC_CPU1_DIMM1_SAA";
23"M_C_CPU1_ALERT_N";
24"RST_M_CD_CPU1_FPGA_N";
25"I3C_SPD_DDRABCD_CPU1_LVC1_SCL";
26"PWRGD_CHC_CPU1_DIMM1";
27"TP_CHC_CPU1_DIMM1_FRU_6";
28"TP_CHC_CPU1_DIMM1_FRU_4";
29"TP_CHC_CPU1_DIMM1_FRU_5";
30"M_C_CPU1_SB_DQS_DN<3>";
31"M_C_CPU1_SA_DQS_DN<9>";
32"M_C_CPU1_SA_DQS_DN<8>";
33"M_C_CPU1_SA_DQS_DN<7>";
34"M_C_CPU1_SA_DQS_DN<5>";
35"M_C_CPU1_SA_DQS_DN<6>";
36"M_C_CPU1_SA_DQS_DN<4>";
37"M_C_CPU1_SA_DQS_DN<3>";
38"M_C_CPU1_SA_DQS_DN<2>";
39"M_C_CPU1_SA_DQS_DN<1>";
40"M_C_CPU1_SA_DQS_DN<0>";
41"M_C_CPU1_SB_DQS_DN<9>";
42"M_C_CPU1_SB_DQS_DN<8>";
43"M_C_CPU1_SB_DQS_DN<7>";
44"M_C_CPU1_SB_DQS_DN<4>";
45"M_C_CPU1_SB_DQS_DN<6>";
46"M_C_CPU1_SB_DQS_DN<5>";
47"M_C_CPU1_SB_DQS_DN<2>";
48"M_C_CPU1_SB_DQS_DN<1>";
49"M_C_CPU1_SB_DQS_DN<0>";
50"M_C_CPU1_SA_DQS_DP<9>";
51"M_C_CPU1_SA_DQS_DP<8>";
52"M_C_CPU1_SB_DQS_DP<9>";
53"M_C_CPU1_SA_DQS_DP<0>";
54"M_C_CPU1_SA_DQS_DP<2>";
55"M_C_CPU1_SA_DQS_DP<1>";
56"M_C_CPU1_SA_DQS_DP<3>";
57"M_C_CPU1_SA_DQS_DP<4>";
58"M_C_CPU1_SA_DQS_DP<5>";
59"M_C_CPU1_SA_DQS_DP<6>";
60"M_C_CPU1_SA_DQS_DP<7>";
61"M_C_CPU1_SB_DQS_DP<1>";
62"M_C_CPU1_SB_DQS_DP<0>";
63"M_C_CPU1_SB_DQS_DP<2>";
64"M_C_CPU1_SB_DQS_DP<3>";
65"M_C_CPU1_SB_DQS_DP<4>";
66"M_C_CPU1_SB_DQS_DP<6>";
67"M_C_CPU1_SB_DQS_DP<5>";
68"M_C_CPU1_SB_DQS_DP<7>";
69"M_C_CPU1_SB_DQS_DP<8>";
70"M_C_CPU1_SA_DQ<23>";
71"M_C_CPU1_SA_DQ<24>";
72"M_C_CPU1_SA_DQ<28>";
73"M_C_CPU1_SB_CS_N<0>";
74"M_C_CPU1_CLK_DN<0>";
75"M_C_CPU1_SA_CB<7>";
76"M_C_CPU1_SB_DQ<29>";
77"M_C_CPU1_SB_DQ<27>";
78"M_C_CPU1_SB_DQ<28>";
79"TP_CHC_CPU1_DIMM1_FRU_0";
80"TP_CHC_CPU1_DIMM1_FRU_1";
81"TP_CHC_CPU1_DIMM1_FRU_2";
82"TP_CHC_CPU1_DIMM1_FRU_3";
83"M_C_CPU1_SB_PAR";
84"M_C_CPU1_SA_PAR";
85"M_C_CPU1_SB_RSP<0>";
86"M_C_CPU1_SA_RSP<0>";
87"M_C_CPU1_SB_DQ<0>";
88"M_C_CPU1_SB_DQ<1>";
89"M_C_CPU1_SB_DQ<2>";
90"M_C_CPU1_SB_DQ<3>";
91"M_C_CPU1_SB_DQ<4>";
92"M_C_CPU1_SB_DQ<5>";
93"M_C_CPU1_SB_DQ<6>";
94"M_C_CPU1_SB_DQ<7>";
95"M_C_CPU1_SB_DQ<8>";
96"M_C_CPU1_SB_DQ<9>";
97"M_C_CPU1_SB_DQ<10>";
98"M_C_CPU1_SB_DQ<11>";
99"M_C_CPU1_SB_DQ<12>";
100"M_C_CPU1_SB_DQ<13>";
101"M_C_CPU1_SB_DQ<14>";
102"M_C_CPU1_SB_DQ<15>";
103"M_C_CPU1_SB_DQ<16>";
104"M_C_CPU1_SB_DQ<17>";
105"M_C_CPU1_SB_DQ<18>";
106"M_C_CPU1_SB_DQ<19>";
107"M_C_CPU1_SB_DQ<20>";
108"M_C_CPU1_SB_DQ<21>";
109"M_C_CPU1_SB_DQ<22>";
110"M_C_CPU1_SB_DQ<23>";
111"M_C_CPU1_SB_DQ<24>";
112"M_C_CPU1_SB_DQ<25>";
113"M_C_CPU1_SB_DQ<26>";
114"M_C_CPU1_SB_DQ<30>";
115"M_C_CPU1_SB_DQ<31>";
116"M_C_CPU1_SA_DQ<0>";
117"M_C_CPU1_SA_DQ<1>";
118"M_C_CPU1_SA_DQ<2>";
119"M_C_CPU1_SA_DQ<3>";
120"M_C_CPU1_SA_DQ<4>";
121"M_C_CPU1_SA_DQ<5>";
122"M_C_CPU1_SA_DQ<6>";
123"M_C_CPU1_SA_DQ<7>";
124"M_C_CPU1_SA_DQ<8>";
125"M_C_CPU1_SA_DQ<9>";
126"M_C_CPU1_SA_DQ<10>";
127"M_C_CPU1_SA_DQ<11>";
128"M_C_CPU1_SA_DQ<12>";
129"M_C_CPU1_SA_DQ<13>";
130"M_C_CPU1_SA_DQ<14>";
131"M_C_CPU1_SA_DQ<15>";
132"M_C_CPU1_SA_DQ<16>";
133"M_C_CPU1_SA_DQ<17>";
134"M_C_CPU1_SA_DQ<18>";
135"M_C_CPU1_SA_DQ<19>";
136"M_C_CPU1_SA_DQ<20>";
137"M_C_CPU1_SA_DQ<21>";
138"M_C_CPU1_SA_DQ<22>";
139"M_C_CPU1_SA_DQ<25>";
140"M_C_CPU1_SA_DQ<26>";
141"M_C_CPU1_SA_DQ<27>";
142"M_C_CPU1_SA_DQ<29>";
143"M_C_CPU1_SA_DQ<30>";
144"M_C_CPU1_SB_CS_N<1>";
145"M_C_CPU1_SA_CS_N<1>";
146"M_C_CPU1_SA_CS_N<0>";
147"M_C_CPU1_CLK_DP<0>";
148"M_C_CPU1_SB_CB<0>";
149"M_C_CPU1_SB_CB<1>";
150"M_C_CPU1_SB_CB<2>";
151"M_C_CPU1_SB_CB<3>";
152"M_C_CPU1_SB_CB<4>";
153"M_C_CPU1_SB_CB<5>";
154"M_C_CPU1_SB_CB<6>";
155"M_C_CPU1_SA_CB<0>";
156"M_C_CPU1_SA_CB<2>";
157"M_C_CPU1_SA_CB<3>";
158"M_C_CPU1_SA_CB<5>";
159"M_C_CPU1_SA_CB<6>";
160"M_C_CPU1_SB_CA<6>";
161"M_C_CPU1_SA_CA<6>";
162"M_C_CPU1_SB_CA<5>";
163"M_C_CPU1_SA_CA<5>";
164"M_C_CPU1_SB_CA<4>";
165"M_C_CPU1_SA_CA<4>";
166"M_C_CPU1_SB_CA<3>";
167"M_C_CPU1_SA_CA<3>";
168"M_C_CPU1_SB_CA<2>";
169"M_C_CPU1_SA_CA<2>";
170"M_C_CPU1_SB_CA<1>";
171"M_C_CPU1_SA_CA<1>";
172"M_C_CPU1_SB_CA<0>";
173"M_C_CPU1_SA_CA<0>";
174"M_C_CPU1_SB_CB<7>";
175"M_C_CPU1_SA_CB<1>";
176"M_C_CPU1_SA_CB<4>";
177"M_C_CPU1_SA_DQ<31>";
178"PD_CHC_CPU1_DIMM1_SAA";
%"UNIVERSAL_GND"
"1","(-2600,-200)","0","logical_power","I1";
;
HDL_POWER"GND"
CDS_LIB"logical_power";
"A"5;
%"TAP"
"1","(-1175,3375)","0","standard","I100";
;
CDS_LIB"standard"
BODY_TYPE"PLUMBING"
HDL_TAP"TRUE";
"B \NAC \NWC"10;
"S \NAC"
BN"15"131;
%"TAP"
"1","(-1175,3475)","0","standard","I101";
;
CDS_LIB"standard"
BODY_TYPE"PLUMBING"
HDL_TAP"TRUE";
"B \NAC \NWC"10;
"S \NAC"
BN"17"133;
%"TAP"
"1","(-1175,3425)","0","standard","I102";
;
CDS_LIB"standard"
BODY_TYPE"PLUMBING"
HDL_TAP"TRUE";
"B \NAC \NWC"10;
"S \NAC"
BN"16"132;
%"TAP"
"1","(-1175,3575)","0","standard","I103";
;
CDS_LIB"standard"
BODY_TYPE"PLUMBING"
HDL_TAP"TRUE";
"B \NAC \NWC"10;
"S \NAC"
BN"19"135;
%"TAP"
"1","(-1175,3525)","0","standard","I104";
;
CDS_LIB"standard"
BODY_TYPE"PLUMBING"
HDL_TAP"TRUE";
"B \NAC \NWC"10;
"S \NAC"
BN"18"134;
%"TAP"
"1","(-1175,3625)","0","standard","I105";
;
CDS_LIB"standard"
BODY_TYPE"PLUMBING"
HDL_TAP"TRUE";
"B \NAC \NWC"10;
"S \NAC"
BN"20"136;
%"TAP"
"1","(-1175,3725)","0","standard","I106";
;
CDS_LIB"standard"
BODY_TYPE"PLUMBING"
HDL_TAP"TRUE";
"B \NAC \NWC"10;
"S \NAC"
BN"22"138;
%"TAP"
"1","(-1175,3675)","0","standard","I107";
;
CDS_LIB"standard"
BODY_TYPE"PLUMBING"
HDL_TAP"TRUE";
"B \NAC \NWC"10;
"S \NAC"
BN"21"137;
%"TAP"
"1","(-1175,3775)","0","standard","I108";
;
CDS_LIB"standard"
BODY_TYPE"PLUMBING"
HDL_TAP"TRUE";
"B \NAC \NWC"10;
"S \NAC"
BN"23"70;
%"TAP"
"1","(-1175,3825)","0","standard","I109";
;
CDS_LIB"standard"
BODY_TYPE"PLUMBING"
HDL_TAP"TRUE";
"B \NAC \NWC"10;
"S \NAC"
BN"24"71;
%"TAP"
"1","(-1175,3925)","0","standard","I110";
;
CDS_LIB"standard"
BODY_TYPE"PLUMBING"
HDL_TAP"TRUE";
"B \NAC \NWC"10;
"S \NAC"
BN"26"140;
%"TAP"
"1","(-1175,3875)","0","standard","I111";
;
CDS_LIB"standard"
BODY_TYPE"PLUMBING"
HDL_TAP"TRUE";
"B \NAC \NWC"10;
"S \NAC"
BN"25"139;
%"TAP"
"1","(-1175,3975)","0","standard","I112";
;
CDS_LIB"standard"
BODY_TYPE"PLUMBING"
HDL_TAP"TRUE";
"B \NAC \NWC"10;
"S \NAC"
BN"27"141;
%"TAP"
"1","(-1175,4075)","0","standard","I113";
;
CDS_LIB"standard"
BODY_TYPE"PLUMBING"
HDL_TAP"TRUE";
"B \NAC \NWC"10;
"S \NAC"
BN"29"142;
%"TAP"
"1","(-1175,4025)","0","standard","I114";
;
CDS_LIB"standard"
BODY_TYPE"PLUMBING"
HDL_TAP"TRUE";
"B \NAC \NWC"10;
"S \NAC"
BN"28"72;
%"TAP"
"1","(-2825,4175)","2","standard","I117";
;
CDS_LIB"standard"
BODY_TYPE"PLUMBING"
HDL_TAP"TRUE";
"B \NAC \NWC"13;
"S \NAC"
BN"6"161;
%"TAP"
"1","(-2825,4125)","2","standard","I118";
;
CDS_LIB"standard"
BODY_TYPE"PLUMBING"
HDL_TAP"TRUE";
"B \NAC \NWC"13;
"S \NAC"
BN"5"163;
%"TAP"
"1","(-1175,4175)","0","standard","I119";
;
CDS_LIB"standard"
BODY_TYPE"PLUMBING"
HDL_TAP"TRUE";
"B \NAC \NWC"10;
"S \NAC"
BN"31"177;
%"VCC_CORE"
"1","(-3650,2050)","0","logical_power","I12";
;
HDL_POWER"P3V3_AUX"
CDS_LIB"logical_power";
"A"4;
%"TAP"
"1","(-1175,4125)","0","standard","I120";
;
CDS_LIB"standard"
BODY_TYPE"PLUMBING"
HDL_TAP"TRUE";
"B \NAC \NWC"10;
"S \NAC"
BN"30"143;
%"UNIVERSAL_GND"
"1","(550,-75)","0","logical_power","I122";
;
HDL_POWER"GND"
CDS_LIB"logical_power";
"A"6;
%"UNIVERSAL_GND"
"1","(2175,-75)","0","logical_power","I123";
;
HDL_POWER"GND"
CDS_LIB"logical_power";
"A"7;
%"Q_CAP"
"1","(550,300)","0","pure_quanta","I124";
;
PART_NUMBER"CH5221MEB00"
VOLTAGE"6.3V"
VALUE"2.2UF"
PACK_TYPE"C0402"
MATERIAL"X6S"
TOLERANCE"20%"
$LOCATION"C62"
CDS_LIB"pure_quanta"
$LOCATION"C62"
CDS_LOCATION"C62"
$SEC"1"
CDS_SEC"1";
"B"
$PN"2"6;
"A"
$PN"1"1;
%"VCC_CORE"
"1","(550,625)","0","logical_power","I125";
;
HDL_POWER"P3V3_AUX"
CDS_LIB"logical_power";
"A"1;
%"Q_CAP"
"1","(1550,300)","0","pure_quanta","I127";
;
PART_NUMBER"CH6103KEA00"
VOLTAGE"16V"
VALUE"10UF"
TOLERANCE"10%"
PACK_TYPE"C0805"
MATERIAL"X6S"
$LOCATION"C63"
CDS_LIB"pure_quanta"
$LOCATION"C63"
CDS_LOCATION"C63"
$SEC"1"
CDS_SEC"1";
"B"
$PN"2"7;
"A"
$PN"1"2;
%"VCC_CORE"
"1","(1550,625)","0","logical_power","I128";
;
HDL_POWER"P12V_S3_AUX_CPU1_NVDIMM"
CDS_LIB"logical_power";
"A"2;
%"TAP"
"1","(1575,2325)","0","standard","I129";
;
CDS_LIB"standard"
BODY_TYPE"PLUMBING"
HDL_TAP"TRUE";
"B \NAC \NWC"16;
"S \NAC"
BN"1"61;
%"SCONN288_ADR50017P130CC"
"1","(-2000,2450)","0","pure_quanta","I13";
;
PART_NUMBER"DFHST8FS461"
MATERIAL"IO"
VALUE"SCONN288_ADR50017-P130CC"
PART_TYPE"SMLF"
$LOCATION"J21"
NEEDS_NO_SIZE"TRUE"
CDS_LMAN_SYM_OUTLINE"-450,1875,450,-1875"
CDS_LIB"pure_quanta"
CDS_LOCATION"J21"
$SEC"1"
CDS_SEC"1";
"DQ31_A"
$PN"194"177;
"CB7_A"
$PN"205"75;
"CB4_A"
$PN"58"176;
"CB1_A"
$PN"53"175;
"CB7_B"
$PN"236"174;
"ALERT_N \B"
$PN"62"23;
"CA0_A"
$PN"66"173;
"CA0_B"
$PN"76"172;
"CA1_A"
$PN"211"171;
"CA1_B"
$PN"221"170;
"CA2_A"
$PN"68"169;
"CA2_B"
$PN"78"168;
"CA3_A"
$PN"213"167;
"CA3_B"
$PN"223"166;
"CA4_A"
$PN"70"165;
"CA4_B"
$PN"80"164;
"CA5_A"
$PN"215"163;
"CA5_B"
$PN"225"162;
"CA6_A"
$PN"72"161;
"CA6_B"
$PN"82"160;
"CB6_A"
$PN"203"159;
"CB5_A"
$PN"60"158;
"CB3_A"
$PN"198"157;
"CB2_A"
$PN"196"156;
"CB0_A"
$PN"51"155;
"CB6_B"
$PN"234"154;
"CB5_B"
$PN"91"153;
"CB4_B"
$PN"89"152;
"CB3_B"
$PN"243"151;
"CB2_B"
$PN"241"150;
"CB1_B"
$PN"98"149;
"CB0_B"
$PN"96"148;
"CK_C \B"
$PN"218"74;
"CK_T"
$PN"217"147;
"CS0_A_N"
$PN"64"146;
"CS0_B_N"
$PN"84"73;
"CS1_A_N"
$PN"209"145;
"CS1_B_N"
$PN"229"144;
"DQ30_A"
$PN"192"143;
"DQ29_A"
$PN"49"142;
"DQ28_A"
$PN"47"72;
"DQ27_A"
$PN"187"141;
"DQ26_A"
$PN"185"140;
"DQ25_A"
$PN"42"139;
"DQ24_A"
$PN"40"71;
"DQ23_A"
$PN"183"70;
"DQ22_A"
$PN"181"138;
"DQ21_A"
$PN"38"137;
"DQ20_A"
$PN"36"136;
"DQ19_A"
$PN"176"135;
"DQ18_A"
$PN"174"134;
"DQ17_A"
$PN"31"133;
"DQ16_A"
$PN"29"132;
"DQ15_A"
$PN"172"131;
"DQ14_A"
$PN"170"130;
"DQ13_A"
$PN"27"129;
"DQ12_A"
$PN"25"128;
"DQ11_A"
$PN"165"127;
"DQ10_A"
$PN"163"126;
"DQ9_A"
$PN"20"125;
"DQ8_A"
$PN"18"124;
"DQ7_A"
$PN"161"123;
"DQ6_A"
$PN"159"122;
"DQ5_A"
$PN"16"121;
"DQ4_A"
$PN"14"120;
"DQ3_A"
$PN"154"119;
"DQ2_A"
$PN"152"118;
"DQ1_A"
$PN"9"117;
"DQ0_A"
$PN"7"116;
"DQ31_B"
$PN"287"115;
"DQ30_B"
$PN"285"114;
"DQ29_B"
$PN"142"76;
"DQ28_B"
$PN"140"78;
"DQ27_B"
$PN"280"77;
"DQ26_B"
$PN"278"113;
"DQ25_B"
$PN"135"112;
"DQ24_B"
$PN"133"111;
"DQ23_B"
$PN"276"110;
"DQ22_B"
$PN"274"109;
"DQ21_B"
$PN"131"108;
"DQ20_B"
$PN"129"107;
"DQ19_B"
$PN"269"106;
"DQ18_B"
$PN"267"105;
"DQ17_B"
$PN"124"104;
"DQ16_B"
$PN"122"103;
"DQ15_B"
$PN"265"102;
"DQ14_B"
$PN"263"101;
"DQ13_B"
$PN"120"100;
"DQ12_B"
$PN"118"99;
"DQ11_B"
$PN"258"98;
"DQ10_B"
$PN"256"97;
"DQ9_B"
$PN"113"96;
"DQ8_B"
$PN"111"95;
"DQ7_B"
$PN"254"94;
"DQ6_B"
$PN"252"93;
"DQ5_B"
$PN"109"92;
"DQ4_B"
$PN"107"91;
"DQ3_B"
$PN"247"90;
"DQ2_B"
$PN"245"89;
"DQ1_B"
$PN"102"88;
"DQ0_B"
$PN"100"87;
"HSA"
$PN"148"22;
"HSCL"
$PN"4"20;
"HSDA"
$PN"5"21;
"LBD||RSP_A_N"
$PN"86"86;
"LBS||RSP_B_N"
$PN"87"85;
"PAR_A"
$PN"74"84;
"PAR_B"
$PN"227"83;
"PWR_GOOD||FAIL_N"
$PN"147"26;
"RESET_N \B"
$PN"207"24;
"RFU6"
$PN"232"27;
"RFU5"
$PN"231"29;
"RFU4"
$PN"220"28;
"RFU3"
$PN"150"82;
"RFU2"
$PN"149"81;
"RFU1"
$PN"144"80;
"RFU0"
$PN"2"79;
"VIN_MGMT"
$PN"3"4;
%"TAP"
"1","(1575,2225)","0","standard","I130";
;
CDS_LIB"standard"
BODY_TYPE"PLUMBING"
HDL_TAP"TRUE";
"B \NAC \NWC"16;
"S \NAC"
BN"0"62;
%"TAP"
"1","(1575,2425)","0","standard","I131";
;
CDS_LIB"standard"
BODY_TYPE"PLUMBING"
HDL_TAP"TRUE";
"B \NAC \NWC"16;
"S \NAC"
BN"2"63;
%"TAP"
"1","(1575,2525)","0","standard","I132";
;
CDS_LIB"standard"
BODY_TYPE"PLUMBING"
HDL_TAP"TRUE";
"B \NAC \NWC"16;
"S \NAC"
BN"3"64;
%"TAP"
"1","(1575,2625)","0","standard","I133";
;
CDS_LIB"standard"
BODY_TYPE"PLUMBING"
HDL_TAP"TRUE";
"B \NAC \NWC"16;
"S \NAC"
BN"4"65;
%"TAP"
"1","(1575,2825)","0","standard","I134";
;
CDS_LIB"standard"
BODY_TYPE"PLUMBING"
HDL_TAP"TRUE";
"B \NAC \NWC"16;
"S \NAC"
BN"6"66;
%"TAP"
"1","(1575,2725)","0","standard","I135";
;
CDS_LIB"standard"
BODY_TYPE"PLUMBING"
HDL_TAP"TRUE";
"B \NAC \NWC"16;
"S \NAC"
BN"5"67;
%"TAP"
"1","(1575,2925)","0","standard","I136";
;
CDS_LIB"standard"
BODY_TYPE"PLUMBING"
HDL_TAP"TRUE";
"B \NAC \NWC"16;
"S \NAC"
BN"7"68;
%"TAP"
"1","(1575,3025)","0","standard","I137";
;
CDS_LIB"standard"
BODY_TYPE"PLUMBING"
HDL_TAP"TRUE";
"B \NAC \NWC"16;
"S \NAC"
BN"8"69;
%"TAP"
"1","(1750,2175)","0","standard","I138";
;
CDS_LIB"standard"
BODY_TYPE"PLUMBING"
HDL_TAP"TRUE";
"B \NAC \NWC"18;
"S \NAC"
BN"0"49;
%"TAP"
"1","(1750,2275)","0","standard","I139";
;
CDS_LIB"standard"
BODY_TYPE"PLUMBING"
HDL_TAP"TRUE";
"B \NAC \NWC"18;
"S \NAC"
BN"1"48;
%"TAP"
"1","(-2825,1975)","2","standard","I14";
;
CDS_LIB"standard"
BODY_TYPE"PLUMBING"
HDL_TAP"TRUE";
"B \NAC \NWC"12;
"S \NAC"
BN"0"148;
%"TAP"
"1","(1750,2375)","0","standard","I140";
;
CDS_LIB"standard"
BODY_TYPE"PLUMBING"
HDL_TAP"TRUE";
"B \NAC \NWC"18;
"S \NAC"
BN"2"47;
%"TAP"
"1","(1750,2475)","0","standard","I141";
;
CDS_LIB"standard"
BODY_TYPE"PLUMBING"
HDL_TAP"TRUE";
"B \NAC \NWC"18;
"S \NAC"
BN"3"30;
%"TAP"
"1","(1750,2575)","0","standard","I142";
;
CDS_LIB"standard"
BODY_TYPE"PLUMBING"
HDL_TAP"TRUE";
"B \NAC \NWC"18;
"S \NAC"
BN"4"44;
%"TAP"
"1","(1750,2675)","0","standard","I143";
;
CDS_LIB"standard"
BODY_TYPE"PLUMBING"
HDL_TAP"TRUE";
"B \NAC \NWC"18;
"S \NAC"
BN"5"46;
%"TAP"
"1","(1750,2775)","0","standard","I144";
;
CDS_LIB"standard"
BODY_TYPE"PLUMBING"
HDL_TAP"TRUE";
"B \NAC \NWC"18;
"S \NAC"
BN"6"45;
%"TAP"
"1","(1750,2875)","0","standard","I145";
;
CDS_LIB"standard"
BODY_TYPE"PLUMBING"
HDL_TAP"TRUE";
"B \NAC \NWC"18;
"S \NAC"
BN"7"43;
%"TAP"
"1","(1750,3075)","0","standard","I146";
;
CDS_LIB"standard"
BODY_TYPE"PLUMBING"
HDL_TAP"TRUE";
"B \NAC \NWC"18;
"S \NAC"
BN"9"41;
%"TAP"
"1","(1750,2975)","0","standard","I147";
;
CDS_LIB"standard"
BODY_TYPE"PLUMBING"
HDL_TAP"TRUE";
"B \NAC \NWC"18;
"S \NAC"
BN"8"42;
%"TAP"
"1","(1575,3125)","0","standard","I148";
;
CDS_LIB"standard"
BODY_TYPE"PLUMBING"
HDL_TAP"TRUE";
"B \NAC \NWC"16;
"S \NAC"
BN"9"52;
%"TAP"
"1","(1575,3275)","0","standard","I149";
;
CDS_LIB"standard"
BODY_TYPE"PLUMBING"
HDL_TAP"TRUE";
"B \NAC \NWC"17;
"S \NAC"
BN"0"53;
%"TAP"
"1","(-2825,2025)","2","standard","I15";
;
CDS_LIB"standard"
BODY_TYPE"PLUMBING"
HDL_TAP"TRUE";
"B \NAC \NWC"12;
"S \NAC"
BN"1"149;
%"TAP"
"1","(1575,3475)","0","standard","I150";
;
CDS_LIB"standard"
BODY_TYPE"PLUMBING"
HDL_TAP"TRUE";
"B \NAC \NWC"17;
"S \NAC"
BN"2"54;
%"TAP"
"1","(1575,3375)","0","standard","I151";
;
CDS_LIB"standard"
BODY_TYPE"PLUMBING"
HDL_TAP"TRUE";
"B \NAC \NWC"17;
"S \NAC"
BN"1"55;
%"TAP"
"1","(1575,3575)","0","standard","I152";
;
CDS_LIB"standard"
BODY_TYPE"PLUMBING"
HDL_TAP"TRUE";
"B \NAC \NWC"17;
"S \NAC"
BN"3"56;
%"TAP"
"1","(1575,3675)","0","standard","I153";
;
CDS_LIB"standard"
BODY_TYPE"PLUMBING"
HDL_TAP"TRUE";
"B \NAC \NWC"17;
"S \NAC"
BN"4"57;
%"TAP"
"1","(1575,3775)","0","standard","I154";
;
CDS_LIB"standard"
BODY_TYPE"PLUMBING"
HDL_TAP"TRUE";
"B \NAC \NWC"17;
"S \NAC"
BN"5"58;
%"TAP"
"1","(1575,3875)","0","standard","I155";
;
CDS_LIB"standard"
BODY_TYPE"PLUMBING"
HDL_TAP"TRUE";
"B \NAC \NWC"17;
"S \NAC"
BN"6"59;
%"TAP"
"1","(1575,3975)","0","standard","I156";
;
CDS_LIB"standard"
BODY_TYPE"PLUMBING"
HDL_TAP"TRUE";
"B \NAC \NWC"17;
"S \NAC"
BN"7"60;
%"TAP"
"1","(1575,4075)","0","standard","I157";
;
CDS_LIB"standard"
BODY_TYPE"PLUMBING"
HDL_TAP"TRUE";
"B \NAC \NWC"17;
"S \NAC"
BN"8"51;
%"TAP"
"1","(1750,3225)","0","standard","I158";
;
CDS_LIB"standard"
BODY_TYPE"PLUMBING"
HDL_TAP"TRUE";
"B \NAC \NWC"19;
"S \NAC"
BN"0"40;
%"TAP"
"1","(1750,3325)","0","standard","I159";
;
CDS_LIB"standard"
BODY_TYPE"PLUMBING"
HDL_TAP"TRUE";
"B \NAC \NWC"19;
"S \NAC"
BN"1"39;
%"TAP"
"1","(1750,3425)","0","standard","I160";
;
CDS_LIB"standard"
BODY_TYPE"PLUMBING"
HDL_TAP"TRUE";
"B \NAC \NWC"19;
"S \NAC"
BN"2"38;
%"TAP"
"1","(1750,3525)","0","standard","I161";
;
CDS_LIB"standard"
BODY_TYPE"PLUMBING"
HDL_TAP"TRUE";
"B \NAC \NWC"19;
"S \NAC"
BN"3"37;
%"TAP"
"1","(1750,3725)","0","standard","I162";
;
CDS_LIB"standard"
BODY_TYPE"PLUMBING"
HDL_TAP"TRUE";
"B \NAC \NWC"19;
"S \NAC"
BN"5"34;
%"TAP"
"1","(1750,3625)","0","standard","I163";
;
CDS_LIB"standard"
BODY_TYPE"PLUMBING"
HDL_TAP"TRUE";
"B \NAC \NWC"19;
"S \NAC"
BN"4"36;
%"TAP"
"1","(1750,3825)","0","standard","I164";
;
CDS_LIB"standard"
BODY_TYPE"PLUMBING"
HDL_TAP"TRUE";
"B \NAC \NWC"19;
"S \NAC"
BN"6"35;
%"TAP"
"1","(1750,3925)","0","standard","I165";
;
CDS_LIB"standard"
BODY_TYPE"PLUMBING"
HDL_TAP"TRUE";
"B \NAC \NWC"19;
"S \NAC"
BN"7"33;
%"TAP"
"1","(1750,4025)","0","standard","I166";
;
CDS_LIB"standard"
BODY_TYPE"PLUMBING"
HDL_TAP"TRUE";
"B \NAC \NWC"19;
"S \NAC"
BN"8"32;
%"Q_CAP"
"1","(2175,300)","0","pure_quanta","I167";
;
PART_NUMBER"CH6103KEA00"
VALUE"10UF"
PACK_TYPE"C0805"
VOLTAGE"16V"
TOLERANCE"10%"
MATERIAL"X6S"
$LOCATION"C64"
CDS_LIB"pure_quanta"
$LOCATION"C64"
CDS_LOCATION"C64"
$SEC"1"
CDS_SEC"1";
"B"
$PN"2"7;
"A"
$PN"1"2;
%"UNIVERSAL_GND"
"1","(3250,475)","0","logical_power","I168";
;
HDL_POWER"GND"
CDS_LIB"logical_power";
"A"8;
%"SCONN288_ADR50017P130CC"
"3","(4100,2550)","0","pure_quanta","I169";
;
PART_NUMBER"DFHST8FS461"
MATERIAL"IO"
PART_TYPE"SMLF"
VALUE"SCONN288_ADR50017-P130CC"
$LOCATION"J21"
NEEDS_NO_SIZE"TRUE"
CDS_LMAN_SYM_OUTLINE"-450,1775,450,-1775"
CDS_LIB"pure_quanta"
CDS_LOCATION"J21"
$SEC"3"
CDS_SEC"3";
"G3"
$PN"G3"9;
"G2"
$PN"G2"9;
"G1"
$PN"G1"9;
"VSS62"
$PN"141"9;
"VSS61"
$PN"139"9;
"VSS60"
$PN"136"9;
"VSS58"
$PN"132"9;
"VSS104"
$PN"240"8;
"VSS102"
$PN"235"8;
"VSS100"
$PN"230"8;
"VIN_BULK2"
$PN"146"3;
"VIN_BULK1"
$PN"145"3;
"VIN_BULK0"
$PN"1"3;
"VSS126"
$PN"288"8;
"VSS125"
$PN"286"8;
"VSS124"
$PN"284"8;
"VSS123"
$PN"281"8;
"VSS122"
$PN"279"8;
"VSS121"
$PN"277"8;
"VSS120"
$PN"275"8;
"VSS119"
$PN"273"8;
"VSS118"
$PN"270"8;
"VSS117"
$PN"268"8;
"VSS116"
$PN"266"8;
"VSS115"
$PN"264"8;
"VSS114"
$PN"262"8;
"VSS113"
$PN"259"8;
"VSS112"
$PN"257"8;
"VSS111"
$PN"255"8;
"VSS110"
$PN"253"8;
"VSS109"
$PN"251"8;
"VSS108"
$PN"248"8;
"VSS107"
$PN"246"8;
"VSS106"
$PN"244"8;
"VSS105"
$PN"242"8;
"VSS103"
$PN"237"8;
"VSS101"
$PN"233"8;
"VSS99"
$PN"228"8;
"VSS98"
$PN"226"8;
"VSS97"
$PN"224"8;
"VSS96"
$PN"222"8;
"VSS95"
$PN"219"8;
"VSS94"
$PN"216"8;
"VSS93"
$PN"214"8;
"VSS92"
$PN"212"8;
"VSS91"
$PN"210"8;
"VSS90"
$PN"208"8;
"VSS89"
$PN"206"8;
"VSS88"
$PN"204"8;
"VSS87"
$PN"202"8;
"VSS86"
$PN"199"8;
"VSS85"
$PN"197"8;
"VSS84"
$PN"195"8;
"VSS83"
$PN"193"8;
"VSS82"
$PN"191"8;
"VSS81"
$PN"188"8;
"VSS80"
$PN"186"8;
"VSS79"
$PN"184"8;
"VSS78"
$PN"182"8;
"VSS77"
$PN"180"8;
"VSS76"
$PN"177"8;
"VSS75"
$PN"175"8;
"VSS74"
$PN"173"8;
"VSS73"
$PN"171"8;
"VSS72"
$PN"169"8;
"VSS71"
$PN"166"8;
"VSS70"
$PN"164"8;
"VSS69"
$PN"162"8;
"VSS68"
$PN"160"8;
"VSS67"
$PN"158"8;
"VSS66"
$PN"155"8;
"VSS65"
$PN"153"8;
"VSS64"
$PN"151"8;
"VSS63"
$PN"143"9;
"VSS59"
$PN"134"9;
"VSS57"
$PN"130"9;
"VSS56"
$PN"128"9;
"VSS55"
$PN"125"9;
"VSS54"
$PN"123"9;
"VSS53"
$PN"121"9;
"VSS52"
$PN"119"9;
"VSS51"
$PN"117"9;
"VSS50"
$PN"114"9;
"VSS49"
$PN"112"9;
"VSS48"
$PN"110"9;
"VSS47"
$PN"108"9;
"VSS46"
$PN"106"9;
"VSS45"
$PN"103"9;
"VSS44"
$PN"101"9;
"VSS43"
$PN"99"9;
"VSS42"
$PN"97"9;
"VSS41"
$PN"95"9;
"VSS40"
$PN"92"9;
"VSS39"
$PN"90"9;
"VSS38"
$PN"88"9;
"VSS37"
$PN"85"9;
"VSS36"
$PN"83"9;
"VSS35"
$PN"81"9;
"VSS34"
$PN"79"9;
"VSS33"
$PN"77"9;
"VSS32"
$PN"75"9;
"VSS31"
$PN"73"9;
"VSS30"
$PN"71"9;
"VSS29"
$PN"69"9;
"VSS28"
$PN"67"9;
"VSS27"
$PN"65"9;
"VSS26"
$PN"63"9;
"VSS25"
$PN"61"9;
"VSS24"
$PN"59"9;
"VSS23"
$PN"57"9;
"VSS22"
$PN"54"9;
"VSS21"
$PN"52"9;
"VSS20"
$PN"50"9;
"VSS19"
$PN"48"9;
"VSS18"
$PN"46"9;
"VSS17"
$PN"43"9;
"VSS16"
$PN"41"9;
"VSS15"
$PN"39"9;
"VSS14"
$PN"37"9;
"VSS13"
$PN"35"9;
"VSS12"
$PN"32"9;
"VSS11"
$PN"30"9;
"VSS10"
$PN"28"9;
"VSS9"
$PN"26"9;
"VSS8"
$PN"24"9;
"VSS7"
$PN"21"9;
"VSS6"
$PN"19"9;
"VSS5"
$PN"17"9;
"VSS4"
$PN"15"9;
"VSS3"
$PN"13"9;
"VSS2"
$PN"10"9;
"VSS1"
$PN"8"9;
"VSS0"
$PN"6"9;
%"TAP"
"1","(1575,4175)","0","standard","I173";
;
CDS_LIB"standard"
BODY_TYPE"PLUMBING"
HDL_TAP"TRUE";
"B \NAC \NWC"17;
"S \NAC"
BN"9"50;
%"TAP"
"1","(1750,4125)","0","standard","I174";
;
CDS_LIB"standard"
BODY_TYPE"PLUMBING"
HDL_TAP"TRUE";
"B \NAC \NWC"19;
"S \NAC"
BN"9"31;
%"VCC_CORE"
"1","(3250,4725)","0","logical_power","I176";
;
HDL_POWER"P12V_S3_AUX_CPU1_NVDIMM"
CDS_LIB"logical_power";
"A"3;
%"UNIVERSAL_GND"
"1","(4950,475)","0","logical_power","I177";
;
HDL_POWER"GND"
CDS_LIB"logical_power";
"A"9;
%"SCONN288_ADR50017P130CC"
"2","(675,3175)","0","pure_quanta","I178";
;
PART_NUMBER"DFHST8FS461"
VALUE"SCONN288_ADR50017-P130CC"
MATERIAL"IO"
PART_TYPE"SMLF"
LOCATION"J21"
CDS_LMAN_SYM_OUTLINE"-600,1150,600,-1150"
CDS_LIB"pure_quanta"
NEEDS_NO_SIZE"TRUE"
$SEC"2"
CDS_SEC"2";
"DQS7_A_C||TDQS7_A_C \B"
$PN"178"33;
"DQS6_A_T||TDQS6_A_T"
$PN"168"59;
"DQS8_B_T||TDQS8_B_T"
$PN"283"69;
"DQS8_B_C||TDQS8_B_C \B"
$PN"282"42;
"DQS7_B_T||TDQS7_B_T"
$PN"272"68;
"DQS0_A_C \B"
$PN"12"40;
"DQS0_A_T"
$PN"11"53;
"DQS0_B_C \B"
$PN"105"49;
"DQS0_B_T"
$PN"104"62;
"DQS1_A_C \B"
$PN"23"39;
"DQS1_A_T"
$PN"22"55;
"DQS1_B_C \B"
$PN"116"48;
"DQS1_B_T"
$PN"115"61;
"DQS2_A_C \B"
$PN"34"38;
"DQS2_A_T"
$PN"33"54;
"DQS2_B_C \B"
$PN"127"47;
"DQS2_B_T"
$PN"126"63;
"DQS3_A_C \B"
$PN"45"37;
"DQS3_A_T"
$PN"44"56;
"DQS3_B_C \B"
$PN"138"30;
"DQS3_B_T"
$PN"137"64;
"DQS4_A_C \B"
$PN"56"36;
"DQS4_A_T"
$PN"55"57;
"DQS4_B_C \B"
$PN"238"44;
"DQS4_B_T"
$PN"239"65;
"DQS5_A_C||TDQS5_A_C||DQS5_A_T||TDQS5_A_T \B"
$PN"156"34;
"DQS5_A_T||TDQS5_A_T"
$PN"157"58;
"DQS5_B_C||TDQS5_B_C \B"
$PN"249"46;
"DQS5_B_T||TDQS5_B_T"
$PN"250"67;
"DQS6_A_C||TDQS6_A_C||DQS6_A_T||TDQS6_A_T \B"
$PN"167"35;
"DQS6_B_C||TDQS6_B_C \B"
$PN"260"45;
"DQS6_B_T||TDQS6_B_T"
$PN"261"66;
"DQS7_A_T||TDQS7_A_T"
$PN"179"60;
"DQS7_B_C||TDQS7_B_C \B"
$PN"271"43;
"DQS8_A_C||TDQS8_A_C \B"
$PN"189"32;
"DQS8_A_T||TDQS8_A_T"
$PN"190"51;
"DQS9_A_C||TDQS9_A_C \B"
$PN"200"31;
"DQS9_A_T||TDQS9_A_T"
$PN"201"50;
"DQS9_B_C||TDQS9_B_C \B"
$PN"94"41;
"DQS9_B_T||TDQS9_B_T||DBI4_B_N"
$PN"93"52;
%"Q_RES"
"1","(-3825,1450)","0","pure_quanta","I180";
;
PART_NUMBER"CS04992FB07"
VALUE"49.9"
MATERIAL"CHIP"
$LOCATION"R3895"
CDS_LIB"pure_quanta"
PACK_TYPE"0402LF"
TOLERANCE"1%"
WATTAGE"1/16W"
CDS_LOCATION"R3895"
$SEC"1"
CDS_SEC"1";
"B"
$PN"2"25;
"A"
$PN"1"20;
%"Q_RES"
"2","(-2600,25)","0","pure_quanta","I2";
;
PART_NUMBER"CS35492FB03"
VALUE"54.9K"
TOLERANCE"1%"
WATTAGE"1/16W"
MATERIAL"CHIP"
PACK_TYPE"0402LF"
$LOCATION"R46"
CDS_LIB"pure_quanta"
$LOCATION"R46"
CDS_LOCATION"R46"
$SEC"1"
CDS_SEC"1";
"A"
$PN"1"178;
"B"
$PN"2"5;
%"TAP"
"1","(-2825,2125)","2","standard","I27";
;
CDS_LIB"standard"
BODY_TYPE"PLUMBING"
HDL_TAP"TRUE";
"B \NAC \NWC"12;
"S \NAC"
BN"3"151;
%"TAP"
"1","(-2825,2075)","2","standard","I28";
;
CDS_LIB"standard"
BODY_TYPE"PLUMBING"
HDL_TAP"TRUE";
"B \NAC \NWC"12;
"S \NAC"
BN"2"150;
%"TAP"
"1","(-2825,2175)","2","standard","I29";
;
CDS_LIB"standard"
BODY_TYPE"PLUMBING"
HDL_TAP"TRUE";
"B \NAC \NWC"12;
"S \NAC"
BN"4"152;
%"TAP"
"1","(-2825,2225)","2","standard","I30";
;
CDS_LIB"standard"
BODY_TYPE"PLUMBING"
HDL_TAP"TRUE";
"B \NAC \NWC"12;
"S \NAC"
BN"5"153;
%"TAP"
"1","(-2825,2275)","2","standard","I31";
;
CDS_LIB"standard"
BODY_TYPE"PLUMBING"
HDL_TAP"TRUE";
"B \NAC \NWC"12;
"S \NAC"
BN"6"154;
%"TAP"
"1","(-2825,2325)","2","standard","I32";
;
CDS_LIB"standard"
BODY_TYPE"PLUMBING"
HDL_TAP"TRUE";
"B \NAC \NWC"12;
"S \NAC"
BN"7"174;
%"TAP"
"1","(-2825,2425)","2","standard","I33";
;
CDS_LIB"standard"
BODY_TYPE"PLUMBING"
HDL_TAP"TRUE";
"B \NAC \NWC"11;
"S \NAC"
BN"0"155;
%"TAP"
"1","(-2825,2525)","2","standard","I34";
;
CDS_LIB"standard"
BODY_TYPE"PLUMBING"
HDL_TAP"TRUE";
"B \NAC \NWC"11;
"S \NAC"
BN"2"156;
%"TAP"
"1","(-2825,2475)","2","standard","I35";
;
CDS_LIB"standard"
BODY_TYPE"PLUMBING"
HDL_TAP"TRUE";
"B \NAC \NWC"11;
"S \NAC"
BN"1"175;
%"TAP"
"1","(-2825,2575)","2","standard","I36";
;
CDS_LIB"standard"
BODY_TYPE"PLUMBING"
HDL_TAP"TRUE";
"B \NAC \NWC"11;
"S \NAC"
BN"3"157;
%"TAP"
"1","(-2825,2675)","2","standard","I37";
;
CDS_LIB"standard"
BODY_TYPE"PLUMBING"
HDL_TAP"TRUE";
"B \NAC \NWC"11;
"S \NAC"
BN"5"158;
%"TAP"
"1","(-2825,2625)","2","standard","I38";
;
CDS_LIB"standard"
BODY_TYPE"PLUMBING"
HDL_TAP"TRUE";
"B \NAC \NWC"11;
"S \NAC"
BN"4"176;
%"TAP"
"1","(-2825,2725)","2","standard","I39";
;
CDS_LIB"standard"
BODY_TYPE"PLUMBING"
HDL_TAP"TRUE";
"B \NAC \NWC"11;
"S \NAC"
BN"6"159;
%"TAP"
"1","(-2825,2775)","2","standard","I40";
;
CDS_LIB"standard"
BODY_TYPE"PLUMBING"
HDL_TAP"TRUE";
"B \NAC \NWC"11;
"S \NAC"
BN"7"75;
%"TAP"
"1","(-2825,3475)","2","standard","I41";
;
CDS_LIB"standard"
BODY_TYPE"PLUMBING"
HDL_TAP"TRUE";
"B \NAC \NWC"14;
"S \NAC"
BN"0"172;
%"TAP"
"1","(-2825,3575)","2","standard","I42";
;
CDS_LIB"standard"
BODY_TYPE"PLUMBING"
HDL_TAP"TRUE";
"B \NAC \NWC"14;
"S \NAC"
BN"2"168;
%"TAP"
"1","(-2825,3525)","2","standard","I43";
;
CDS_LIB"standard"
BODY_TYPE"PLUMBING"
HDL_TAP"TRUE";
"B \NAC \NWC"14;
"S \NAC"
BN"1"170;
%"TAP"
"1","(-2825,3625)","2","standard","I44";
;
CDS_LIB"standard"
BODY_TYPE"PLUMBING"
HDL_TAP"TRUE";
"B \NAC \NWC"14;
"S \NAC"
BN"3"166;
%"TAP"
"1","(-2825,3675)","2","standard","I45";
;
CDS_LIB"standard"
BODY_TYPE"PLUMBING"
HDL_TAP"TRUE";
"B \NAC \NWC"14;
"S \NAC"
BN"4"164;
%"TAP"
"1","(-2825,3725)","2","standard","I46";
;
CDS_LIB"standard"
BODY_TYPE"PLUMBING"
HDL_TAP"TRUE";
"B \NAC \NWC"14;
"S \NAC"
BN"5"162;
%"TAP"
"1","(-2825,3775)","2","standard","I47";
;
CDS_LIB"standard"
BODY_TYPE"PLUMBING"
HDL_TAP"TRUE";
"B \NAC \NWC"14;
"S \NAC"
BN"6"160;
%"TAP"
"1","(-2825,3925)","2","standard","I48";
;
CDS_LIB"standard"
BODY_TYPE"PLUMBING"
HDL_TAP"TRUE";
"B \NAC \NWC"13;
"S \NAC"
BN"1"171;
%"TAP"
"1","(-2825,3875)","2","standard","I49";
;
CDS_LIB"standard"
BODY_TYPE"PLUMBING"
HDL_TAP"TRUE";
"B \NAC \NWC"13;
"S \NAC"
BN"0"173;
%"TAP"
"1","(-2825,3975)","2","standard","I50";
;
CDS_LIB"standard"
BODY_TYPE"PLUMBING"
HDL_TAP"TRUE";
"B \NAC \NWC"13;
"S \NAC"
BN"2"169;
%"TAP"
"1","(-2825,4075)","2","standard","I51";
;
CDS_LIB"standard"
BODY_TYPE"PLUMBING"
HDL_TAP"TRUE";
"B \NAC \NWC"13;
"S \NAC"
BN"4"165;
%"TAP"
"1","(-2825,4025)","2","standard","I52";
;
CDS_LIB"standard"
BODY_TYPE"PLUMBING"
HDL_TAP"TRUE";
"B \NAC \NWC"13;
"S \NAC"
BN"3"167;
%"TAP"
"1","(-1175,1025)","0","standard","I53";
;
CDS_LIB"standard"
BODY_TYPE"PLUMBING"
HDL_TAP"TRUE";
"B \NAC \NWC"15;
"S \NAC"
BN"1"88;
%"TAP"
"1","(-1175,975)","0","standard","I54";
;
CDS_LIB"standard"
BODY_TYPE"PLUMBING"
HDL_TAP"TRUE";
"B \NAC \NWC"15;
"S \NAC"
BN"0"87;
%"TAP"
"1","(-1175,1075)","0","standard","I55";
;
CDS_LIB"standard"
BODY_TYPE"PLUMBING"
HDL_TAP"TRUE";
"B \NAC \NWC"15;
"S \NAC"
BN"2"89;
%"TAP"
"1","(-1175,1175)","0","standard","I56";
;
CDS_LIB"standard"
BODY_TYPE"PLUMBING"
HDL_TAP"TRUE";
"B \NAC \NWC"15;
"S \NAC"
BN"4"91;
%"TAP"
"1","(-1175,1125)","0","standard","I57";
;
CDS_LIB"standard"
BODY_TYPE"PLUMBING"
HDL_TAP"TRUE";
"B \NAC \NWC"15;
"S \NAC"
BN"3"90;
%"TAP"
"1","(-1175,1225)","0","standard","I58";
;
CDS_LIB"standard"
BODY_TYPE"PLUMBING"
HDL_TAP"TRUE";
"B \NAC \NWC"15;
"S \NAC"
BN"5"92;
%"TAP"
"1","(-1175,1275)","0","standard","I59";
;
CDS_LIB"standard"
BODY_TYPE"PLUMBING"
HDL_TAP"TRUE";
"B \NAC \NWC"15;
"S \NAC"
BN"6"93;
%"TAP"
"1","(-1175,1325)","0","standard","I60";
;
CDS_LIB"standard"
BODY_TYPE"PLUMBING"
HDL_TAP"TRUE";
"B \NAC \NWC"15;
"S \NAC"
BN"7"94;
%"TAP"
"1","(-1175,1375)","0","standard","I61";
;
CDS_LIB"standard"
BODY_TYPE"PLUMBING"
HDL_TAP"TRUE";
"B \NAC \NWC"15;
"S \NAC"
BN"8"95;
%"TAP"
"1","(-1175,1425)","0","standard","I62";
;
CDS_LIB"standard"
BODY_TYPE"PLUMBING"
HDL_TAP"TRUE";
"B \NAC \NWC"15;
"S \NAC"
BN"9"96;
%"TAP"
"1","(-1175,1525)","0","standard","I63";
;
CDS_LIB"standard"
BODY_TYPE"PLUMBING"
HDL_TAP"TRUE";
"B \NAC \NWC"15;
"S \NAC"
BN"11"98;
%"TAP"
"1","(-1175,1475)","0","standard","I64";
;
CDS_LIB"standard"
BODY_TYPE"PLUMBING"
HDL_TAP"TRUE";
"B \NAC \NWC"15;
"S \NAC"
BN"10"97;
%"TAP"
"1","(-1175,1575)","0","standard","I65";
;
CDS_LIB"standard"
BODY_TYPE"PLUMBING"
HDL_TAP"TRUE";
"B \NAC \NWC"15;
"S \NAC"
BN"12"99;
%"TAP"
"1","(-1175,1625)","0","standard","I66";
;
CDS_LIB"standard"
BODY_TYPE"PLUMBING"
HDL_TAP"TRUE";
"B \NAC \NWC"15;
"S \NAC"
BN"13"100;
%"TAP"
"1","(-1175,1675)","0","standard","I67";
;
CDS_LIB"standard"
BODY_TYPE"PLUMBING"
HDL_TAP"TRUE";
"B \NAC \NWC"15;
"S \NAC"
BN"14"101;
%"TAP"
"1","(-1175,1725)","0","standard","I68";
;
CDS_LIB"standard"
BODY_TYPE"PLUMBING"
HDL_TAP"TRUE";
"B \NAC \NWC"15;
"S \NAC"
BN"15"102;
%"TAP"
"1","(-1175,1775)","0","standard","I69";
;
CDS_LIB"standard"
BODY_TYPE"PLUMBING"
HDL_TAP"TRUE";
"B \NAC \NWC"15;
"S \NAC"
BN"16"103;
%"TAP"
"1","(-1175,1825)","0","standard","I70";
;
CDS_LIB"standard"
BODY_TYPE"PLUMBING"
HDL_TAP"TRUE";
"B \NAC \NWC"15;
"S \NAC"
BN"17"104;
%"TAP"
"1","(-1175,1875)","0","standard","I71";
;
CDS_LIB"standard"
BODY_TYPE"PLUMBING"
HDL_TAP"TRUE";
"B \NAC \NWC"15;
"S \NAC"
BN"18"105;
%"TAP"
"1","(-1175,1925)","0","standard","I72";
;
CDS_LIB"standard"
BODY_TYPE"PLUMBING"
HDL_TAP"TRUE";
"B \NAC \NWC"15;
"S \NAC"
BN"19"106;
%"TAP"
"1","(-1175,2025)","0","standard","I73";
;
CDS_LIB"standard"
BODY_TYPE"PLUMBING"
HDL_TAP"TRUE";
"B \NAC \NWC"15;
"S \NAC"
BN"21"108;
%"TAP"
"1","(-1175,1975)","0","standard","I74";
;
CDS_LIB"standard"
BODY_TYPE"PLUMBING"
HDL_TAP"TRUE";
"B \NAC \NWC"15;
"S \NAC"
BN"20"107;
%"TAP"
"1","(-1175,2075)","0","standard","I75";
;
CDS_LIB"standard"
BODY_TYPE"PLUMBING"
HDL_TAP"TRUE";
"B \NAC \NWC"15;
"S \NAC"
BN"22"109;
%"TAP"
"1","(-1175,2125)","0","standard","I76";
;
CDS_LIB"standard"
BODY_TYPE"PLUMBING"
HDL_TAP"TRUE";
"B \NAC \NWC"15;
"S \NAC"
BN"23"110;
%"TAP"
"1","(-1175,2175)","0","standard","I77";
;
CDS_LIB"standard"
BODY_TYPE"PLUMBING"
HDL_TAP"TRUE";
"B \NAC \NWC"15;
"S \NAC"
BN"24"111;
%"TAP"
"1","(-1175,2225)","0","standard","I78";
;
CDS_LIB"standard"
BODY_TYPE"PLUMBING"
HDL_TAP"TRUE";
"B \NAC \NWC"15;
"S \NAC"
BN"25"112;
%"TAP"
"1","(-1175,2325)","0","standard","I79";
;
CDS_LIB"standard"
BODY_TYPE"PLUMBING"
HDL_TAP"TRUE";
"B \NAC \NWC"15;
"S \NAC"
BN"27"77;
%"TAP"
"1","(-1175,2275)","0","standard","I80";
;
CDS_LIB"standard"
BODY_TYPE"PLUMBING"
HDL_TAP"TRUE";
"B \NAC \NWC"15;
"S \NAC"
BN"26"113;
%"TAP"
"1","(-1175,2375)","0","standard","I81";
;
CDS_LIB"standard"
BODY_TYPE"PLUMBING"
HDL_TAP"TRUE";
"B \NAC \NWC"15;
"S \NAC"
BN"28"78;
%"TAP"
"1","(-1175,2425)","0","standard","I82";
;
CDS_LIB"standard"
BODY_TYPE"PLUMBING"
HDL_TAP"TRUE";
"B \NAC \NWC"15;
"S \NAC"
BN"29"76;
%"TAP"
"1","(-1175,2525)","0","standard","I83";
;
CDS_LIB"standard"
BODY_TYPE"PLUMBING"
HDL_TAP"TRUE";
"B \NAC \NWC"15;
"S \NAC"
BN"31"115;
%"TAP"
"1","(-1175,2475)","0","standard","I84";
;
CDS_LIB"standard"
BODY_TYPE"PLUMBING"
HDL_TAP"TRUE";
"B \NAC \NWC"15;
"S \NAC"
BN"30"114;
%"TAP"
"1","(-1175,2625)","0","standard","I85";
;
CDS_LIB"standard"
BODY_TYPE"PLUMBING"
HDL_TAP"TRUE";
"B \NAC \NWC"10;
"S \NAC"
BN"0"116;
%"TAP"
"1","(-1175,2675)","0","standard","I86";
;
CDS_LIB"standard"
BODY_TYPE"PLUMBING"
HDL_TAP"TRUE";
"B \NAC \NWC"10;
"S \NAC"
BN"1"117;
%"TAP"
"1","(-1175,2725)","0","standard","I87";
;
CDS_LIB"standard"
BODY_TYPE"PLUMBING"
HDL_TAP"TRUE";
"B \NAC \NWC"10;
"S \NAC"
BN"2"118;
%"TAP"
"1","(-1175,2775)","0","standard","I88";
;
CDS_LIB"standard"
BODY_TYPE"PLUMBING"
HDL_TAP"TRUE";
"B \NAC \NWC"10;
"S \NAC"
BN"3"119;
%"TAP"
"1","(-1175,2825)","0","standard","I89";
;
CDS_LIB"standard"
BODY_TYPE"PLUMBING"
HDL_TAP"TRUE";
"B \NAC \NWC"10;
"S \NAC"
BN"4"120;
%"TAP"
"1","(-1175,2875)","0","standard","I90";
;
CDS_LIB"standard"
BODY_TYPE"PLUMBING"
HDL_TAP"TRUE";
"B \NAC \NWC"10;
"S \NAC"
BN"5"121;
%"TAP"
"1","(-1175,2925)","0","standard","I91";
;
CDS_LIB"standard"
BODY_TYPE"PLUMBING"
HDL_TAP"TRUE";
"B \NAC \NWC"10;
"S \NAC"
BN"6"122;
%"TAP"
"1","(-1175,2975)","0","standard","I92";
;
CDS_LIB"standard"
BODY_TYPE"PLUMBING"
HDL_TAP"TRUE";
"B \NAC \NWC"10;
"S \NAC"
BN"7"123;
%"TAP"
"1","(-1175,3025)","0","standard","I93";
;
CDS_LIB"standard"
BODY_TYPE"PLUMBING"
HDL_TAP"TRUE";
"B \NAC \NWC"10;
"S \NAC"
BN"8"124;
%"TAP"
"1","(-1175,3075)","0","standard","I94";
;
CDS_LIB"standard"
BODY_TYPE"PLUMBING"
HDL_TAP"TRUE";
"B \NAC \NWC"10;
"S \NAC"
BN"9"125;
%"TAP"
"1","(-1175,3125)","0","standard","I95";
;
CDS_LIB"standard"
BODY_TYPE"PLUMBING"
HDL_TAP"TRUE";
"B \NAC \NWC"10;
"S \NAC"
BN"10"126;
%"TAP"
"1","(-1175,3175)","0","standard","I96";
;
CDS_LIB"standard"
BODY_TYPE"PLUMBING"
HDL_TAP"TRUE";
"B \NAC \NWC"10;
"S \NAC"
BN"11"127;
%"TAP"
"1","(-1175,3225)","0","standard","I97";
;
CDS_LIB"standard"
BODY_TYPE"PLUMBING"
HDL_TAP"TRUE";
"B \NAC \NWC"10;
"S \NAC"
BN"12"128;
%"TAP"
"1","(-1175,3325)","0","standard","I98";
;
CDS_LIB"standard"
BODY_TYPE"PLUMBING"
HDL_TAP"TRUE";
"B \NAC \NWC"10;
"S \NAC"
BN"14"130;
%"TAP"
"1","(-1175,3275)","0","standard","I99";
;
CDS_LIB"standard"
BODY_TYPE"PLUMBING"
HDL_TAP"TRUE";
"B \NAC \NWC"10;
"S \NAC"
BN"13"129;
END.
